# T6G (Grand Teton) — schematic netlist excerpt (pin names and nets, part order shuffled) for the footprints in the layout excerpt that follows; sources: Cadence DE-HDL packaged netlist, KiCad conversion of 04192023_DAF0TMB3IC0_F0TG_MB_C_brd_V02_OCP.brd

PC6017  Q_CAP  0.22UF 25V 10% X7R  pkg C0402  page 270 : A = SW_P1V2_AUX_BT_R ; B = SW_P1V2_AUX_PH
PR97  Q_RES  8.87K 1% EMPTY  pkg 0402LF  page 205 : A = PVDDIO_P0_LSET2 ; B = GND
H33  HOLE  EMPTY  pkg TH  page 230 : \1\ = GND

(kicad_pcb
	(version 20260206)
	(generator "pcbnew")
	(generator_version "10.0")
	(general
		(thickness 1.6)
		(legacy_teardrops no)
	)
	(paper "A4")
	(title_block
		(title "04192023_DAF0TMB3IC0_F0TG_MB_C_brd_V02_OCP.brd")
		(comment 1 "Grand Teton / footprints 1444-1446 of 8354")
	)
	(layers
		(0 "F.Cu" signal "TOP")
		(4 "In1.Cu" signal "GND")
		(6 "In2.Cu" signal "IN1")
		(8 "In3.Cu" signal "GND1")
		(10 "In4.Cu" signal "IN2")
		(12 "In5.Cu" signal "GND2")
		(14 "In6.Cu" signal "IN3")
		(16 "In7.Cu" signal "GND3")
		(18 "In8.Cu" signal "VCC")
		(20 "In9.Cu" signal "VCC1")
		(22 "In10.Cu" signal "GND4")
		(24 "In11.Cu" signal "IN4")
		(26 "In12.Cu" signal "GND5")
		(28 "In13.Cu" signal "IN5")
		(30 "In14.Cu" signal "GND6")
		(32 "In15.Cu" signal "IN6")
		(34 "In16.Cu" signal "GND7")
		(2 "B.Cu" signal "BOTTOM")
		(9 "F.Adhes" user "F.Adhesive")
		(11 "B.Adhes" user "B.Adhesive")
		(13 "F.Paste" user "Package Geometry/Pastemask Top")
		(15 "B.Paste" user "Package Geometry/Pastemask Bottom")
		(5 "F.SilkS" user "Ref Des/Silkscreen Top")
		(7 "B.SilkS" user "Ref Des/Silkscreen Bottom")
		(1 "F.Mask" user "Board Geometry/Soldermask Top")
		(3 "B.Mask" user "Board Geometry/Soldermask Bottom")
		(17 "Dwgs.User" user "User.Drawings")
		(19 "Cmts.User" user "User.Comments")
		(21 "Eco1.User" user "User.Eco1")
		(23 "Eco2.User" user "User.Eco2")
		(25 "Edge.Cuts" user "Board Geometry/Outline")
		(27 "Margin" user)
		(31 "F.CrtYd" user "Package Geometry/Place Bound Top")
		(29 "B.CrtYd" user "Package Geometry/Place Bound Bottom")
		(35 "F.Fab" user "Ref Des/Assembly Top")
		(33 "B.Fab" user "Ref Des/Assembly Bottom")
	)
	(footprint ""
		(layer "F.Cu")
		(at 290.703762 -351.927922)
		(property "Reference" "PR97"
			(at 0 0 0)
			(layer "F.SilkS")
			(hide yes)
			(effects
				(font
					(size 1.27 1.27)
				)
			)
		)
		(property "Value" ""
			(at 0 0 0)
			(layer "F.Fab")
			(effects
				(font
					(size 1.27 1.27)
				)
			)
		)
		(duplicate_pad_numbers_are_jumpers no)
		(fp_line
			(start -0.7874 -0.4064)
			(end 0.7874 -0.4064)
			(stroke
				(width 0.1524)
				(type default)
			)
			(layer "F.SilkS")
		)
		(fp_line
			(start -0.7874 0.4064)
			(end -0.7874 -0.4064)
			(stroke
				(width 0.1524)
				(type default)
			)
			(layer "F.SilkS")
		)
		(fp_line
			(start 0.7874 -0.4064)
			(end 0.7874 0.4064)
			(stroke
				(width 0.1524)
				(type default)
			)
			(layer "F.SilkS")
		)
		(fp_line
			(start 0.7874 0.4064)
			(end -0.7874 0.4064)
			(stroke
				(width 0.1524)
				(type default)
			)
			(layer "F.SilkS")
		)
		(fp_line
			(start -0.67945 -0.305054)
			(end -0.12065 -0.305054)
			(stroke
				(width 0.1)
				(type default)
			)
			(layer "F.Fab")
		)
		(fp_line
			(start -0.67945 0.3048)
			(end -0.67945 -0.305054)
			(stroke
				(width 0.1)
				(type default)
			)
			(layer "F.Fab")
		)
		(fp_line
			(start -0.12065 -0.305054)
			(end -0.12065 -0.2794)
			(stroke
				(width 0.1)
				(type default)
			)
			(layer "F.Fab")
		)
		(fp_line
			(start -0.12065 -0.2794)
			(end 0.12065 -0.2794)
			(stroke
				(width 0.1)
				(type default)
			)
			(layer "F.Fab")
		)
		(fp_line
			(start -0.12065 0.2794)
			(end -0.12065 0.3048)
			(stroke
				(width 0.1)
				(type default)
			)
			(layer "F.Fab")
		)
		(fp_line
			(start -0.12065 0.3048)
			(end -0.67945 0.3048)
			(stroke
				(width 0.1)
				(type default)
			)
			(layer "F.Fab")
		)
		(fp_line
			(start 0.120396 0.2794)
			(end -0.12065 0.2794)
			(stroke
				(width 0.1)
				(type default)
			)
			(layer "F.Fab")
		)
		(fp_line
			(start 0.120396 0.3048)
			(end 0.120396 0.2794)
			(stroke
				(width 0.1)
				(type default)
			)
			(layer "F.Fab")
		)
		(fp_line
			(start 0.12065 -0.3048)
			(end 0.67945 -0.3048)
			(stroke
				(width 0.1)
				(type default)
			)
			(layer "F.Fab")
		)
		(fp_line
			(start 0.12065 -0.2794)
			(end 0.12065 -0.3048)
			(stroke
				(width 0.1)
				(type default)
			)
			(layer "F.Fab")
		)
		(fp_line
			(start 0.67945 -0.3048)
			(end 0.67945 0.3048)
			(stroke
				(width 0.1)
				(type default)
			)
			(layer "F.Fab")
		)
		(fp_line
			(start 0.67945 0.3048)
			(end 0.120396 0.3048)
			(stroke
				(width 0.1)
				(type default)
			)
			(layer "F.Fab")
		)
		(pad "1" smd circle
			(at -0.40005 0)
			(size 0 0)
			(layers "F.Cu" "F.Mask" "F.Paste")
			(net "PVDDIO_P0_LSET2")
		)
		(pad "2" smd circle
			(at 0.40005 0)
			(size 0 0)
			(layers "F.Cu" "F.Mask" "F.Paste")
			(net "GND")
		)
	)
	(footprint ""
		(layer "F.Cu")
		(at 124.088652 -76.251562 90)
		(property "Reference" "PC6017"
			(at 0 0 90)
			(layer "F.SilkS")
			(hide yes)
			(effects
				(font
					(size 1.27 1.27)
				)
			)
		)
		(property "Value" ""
			(at 0 0 90)
			(layer "F.Fab")
			(effects
				(font
					(size 1.27 1.27)
				)
			)
		)
		(duplicate_pad_numbers_are_jumpers no)
		(fp_line
			(start 0.7874 -0.4064)
			(end 0.7874 0.4064)
			(stroke
				(width 0.1524)
				(type default)
			)
			(layer "F.SilkS")
		)
		(fp_line
			(start -0.7874 -0.4064)
			(end 0.7874 -0.4064)
			(stroke
				(width 0.1524)
				(type default)
			)
			(layer "F.SilkS")
		)
		(fp_line
			(start 0.7874 0.4064)
			(end -0.7874 0.4064)
			(stroke
				(width 0.1524)
				(type default)
			)
			(layer "F.SilkS")
		)
		(fp_line
			(start -0.7874 0.4064)
			(end -0.7874 -0.4064)
			(stroke
				(width 0.1524)
				(type default)
			)
			(layer "F.SilkS")
		)
		(fp_line
			(start -0.12065 -0.305054)
			(end -0.12065 -0.2794)
			(stroke
				(width 0.1)
				(type default)
			)
			(layer "F.Fab")
		)
		(fp_line
			(start -0.67945 -0.305054)
			(end -0.12065 -0.305054)
			(stroke
				(width 0.1)
				(type default)
			)
			(layer "F.Fab")
		)
		(fp_line
			(start 0.67945 -0.3048)
			(end 0.67945 0.3048)
			(stroke
				(width 0.1)
				(type default)
			)
			(layer "F.Fab")
		)
		(fp_line
			(start 0.12065 -0.3048)
			(end 0.67945 -0.3048)
			(stroke
				(width 0.1)
				(type default)
			)
			(layer "F.Fab")
		)
		(fp_line
			(start 0.12065 -0.2794)
			(end 0.12065 -0.3048)
			(stroke
				(width 0.1)
				(type default)
			)
			(layer "F.Fab")
		)
		(fp_line
			(start -0.12065 -0.2794)
			(end 0.12065 -0.2794)
			(stroke
				(width 0.1)
				(type default)
			)
			(layer "F.Fab")
		)
		(fp_line
			(start 0.120396 0.2794)
			(end -0.12065 0.2794)
			(stroke
				(width 0.1)
				(type default)
			)
			(layer "F.Fab")
		)
		(fp_line
			(start -0.12065 0.2794)
			(end -0.12065 0.3048)
			(stroke
				(width 0.1)
				(type default)
			)
			(layer "F.Fab")
		)
		(fp_line
			(start 0.67945 0.3048)
			(end 0.120396 0.3048)
			(stroke
				(width 0.1)
				(type default)
			)
			(layer "F.Fab")
		)
		(fp_line
			(start 0.120396 0.3048)
			(end 0.120396 0.2794)
			(stroke
				(width 0.1)
				(type default)
			)
			(layer "F.Fab")
		)
		(fp_line
			(start -0.12065 0.3048)
			(end -0.67945 0.3048)
			(stroke
				(width 0.1)
				(type default)
			)
			(layer "F.Fab")
		)
		(fp_line
			(start -0.67945 0.3048)
			(end -0.67945 -0.305054)
			(stroke
				(width 0.1)
				(type default)
			)
			(layer "F.Fab")
		)
		(pad "1" smd circle
			(at -0.40005 0 90)
			(size 0 0)
			(layers "F.Cu" "F.Mask" "F.Paste")
			(net "SW_P1V2_AUX_BT_R")
		)
		(pad "2" smd circle
			(at 0.40005 0 90)
			(size 0 0)
			(layers "F.Cu" "F.Mask" "F.Paste")
			(net "SW_P1V2_AUX_PH")
		)
	)
	(footprint ""
		(layer "F.Cu")
		(at 413.951928 -351.414842)
		(property "Reference" "H33"
			(at -4.175506 -4.435348 0)
			(unlocked yes)
			(layer "F.SilkS")
			(effects
				(font
					(size 0.7874 0.5842)
					(thickness 0.1524)
				)
				(justify left)
			)
		)
		(property "Value" ""
			(at 0 0 0)
			(layer "F.Fab")
			(effects
				(font
					(size 1.27 1.27)
				)
			)
		)
		(duplicate_pad_numbers_are_jumpers no)
		(pad "1" thru_hole circle
			(at 0 0)
			(size 6.1976 6.1976)
			(drill 3.7338)
			(layers "*.Cu" "*.Mask")
			(remove_unused_layers no)
			(net "GND")
			(clearance -0.9779)
			(padstack
				(mode front_inner_back)
				(layer "Inner"
					(shape circle)
					(size 5.5372 5.5372)
					(clearance -0.6477)
				)
				(layer "B.Cu"
					(shape circle)
					(size 6.1976 6.1976)
					(clearance -0.9779)
				)
			)
		)
	)
)
